# T6G (Grand Teton) — schematic netlist excerpt (pin names and nets, part order shuffled) for the footprints in the layout excerpt that follows; sources: Cadence DE-HDL packaged netlist, KiCad conversion of 04192023_DAF0TMB3IC0_F0TG_MB_C_brd_V02_OCP.brd

R359  Q_RES  1K 1% CHIP  pkg 0402LF  page 161 : A = PVDD11_S3_P1 ; B = SMB_APML_CPU1_SDA
C11  Q_CAP  0.1UF 25V 10% X7R  pkg 0402  page 161 : A = P3V3_AUX ; B = GND

(kicad_pcb
	(version 20260206)
	(generator "pcbnew")
	(generator_version "10.0")
	(general
		(thickness 1.6)
		(legacy_teardrops no)
	)
	(paper "A4")
	(title_block
		(title "04192023_DAF0TMB3IC0_F0TG_MB_C_brd_V02_OCP.brd")
		(comment 1 "Grand Teton / footprints 7363-7364 of 8354")
	)
	(layers
		(0 "F.Cu" signal "TOP")
		(4 "In1.Cu" signal "GND")
		(6 "In2.Cu" signal "IN1")
		(8 "In3.Cu" signal "GND1")
		(10 "In4.Cu" signal "IN2")
		(12 "In5.Cu" signal "GND2")
		(14 "In6.Cu" signal "IN3")
		(16 "In7.Cu" signal "GND3")
		(18 "In8.Cu" signal "VCC")
		(20 "In9.Cu" signal "VCC1")
		(22 "In10.Cu" signal "GND4")
		(24 "In11.Cu" signal "IN4")
		(26 "In12.Cu" signal "GND5")
		(28 "In13.Cu" signal "IN5")
		(30 "In14.Cu" signal "GND6")
		(32 "In15.Cu" signal "IN6")
		(34 "In16.Cu" signal "GND7")
		(2 "B.Cu" signal "BOTTOM")
		(9 "F.Adhes" user "F.Adhesive")
		(11 "B.Adhes" user "B.Adhesive")
		(13 "F.Paste" user "Package Geometry/Pastemask Top")
		(15 "B.Paste" user "Package Geometry/Pastemask Bottom")
		(5 "F.SilkS" user "Ref Des/Silkscreen Top")
		(7 "B.SilkS" user "Ref Des/Silkscreen Bottom")
		(1 "F.Mask" user "Board Geometry/Soldermask Top")
		(3 "B.Mask" user "Board Geometry/Soldermask Bottom")
		(17 "Dwgs.User" user "User.Drawings")
		(19 "Cmts.User" user "User.Comments")
		(21 "Eco1.User" user "User.Eco1")
		(23 "Eco2.User" user "User.Eco2")
		(25 "Edge.Cuts" user "Board Geometry/Outline")
		(27 "Margin" user)
		(31 "F.CrtYd" user "Package Geometry/Place Bound Top")
		(29 "B.CrtYd" user "Package Geometry/Place Bound Bottom")
		(35 "F.Fab" user "Ref Des/Assembly Top")
		(33 "B.Fab" user "Ref Des/Assembly Bottom")
	)
	(footprint ""
		(layer "B.Cu")
		(at 232.857802 -251.042678 -90)
		(property "Reference" "C11"
			(at 0 0 90)
			(layer "B.SilkS")
			(hide yes)
			(effects
				(font
					(size 1.27 1.27)
				)
				(justify mirror)
			)
		)
		(property "Value" ""
			(at 0 0 90)
			(layer "B.Fab")
			(effects
				(font
					(size 1.27 1.27)
				)
				(justify mirror)
			)
		)
		(duplicate_pad_numbers_are_jumpers no)
		(fp_line
			(start -0.7874 0.4064)
			(end 0.7874 0.4064)
			(stroke
				(width 0.1524)
				(type default)
			)
			(layer "B.SilkS")
		)
		(fp_line
			(start 0.7874 0.4064)
			(end 0.7874 -0.4064)
			(stroke
				(width 0.1524)
				(type default)
			)
			(layer "B.SilkS")
		)
		(fp_line
			(start -0.7874 -0.4064)
			(end -0.7874 0.4064)
			(stroke
				(width 0.1524)
				(type default)
			)
			(layer "B.SilkS")
		)
		(fp_line
			(start 0.7874 -0.4064)
			(end -0.7874 -0.4064)
			(stroke
				(width 0.1524)
				(type default)
			)
			(layer "B.SilkS")
		)
		(fp_line
			(start -0.67945 0.3048)
			(end -0.120396 0.3048)
			(stroke
				(width 0.1)
				(type default)
			)
			(layer "B.Fab")
		)
		(fp_line
			(start -0.120396 0.3048)
			(end -0.120396 0.2794)
			(stroke
				(width 0.1)
				(type default)
			)
			(layer "B.Fab")
		)
		(fp_line
			(start 0.12065 0.3048)
			(end 0.67945 0.3048)
			(stroke
				(width 0.1)
				(type default)
			)
			(layer "B.Fab")
		)
		(fp_line
			(start 0.67945 0.3048)
			(end 0.67945 -0.305054)
			(stroke
				(width 0.1)
				(type default)
			)
			(layer "B.Fab")
		)
		(fp_line
			(start -0.120396 0.2794)
			(end 0.12065 0.2794)
			(stroke
				(width 0.1)
				(type default)
			)
			(layer "B.Fab")
		)
		(fp_line
			(start 0.12065 0.2794)
			(end 0.12065 0.3048)
			(stroke
				(width 0.1)
				(type default)
			)
			(layer "B.Fab")
		)
		(fp_line
			(start -0.12065 -0.2794)
			(end -0.12065 -0.3048)
			(stroke
				(width 0.1)
				(type default)
			)
			(layer "B.Fab")
		)
		(fp_line
			(start 0.12065 -0.2794)
			(end -0.12065 -0.2794)
			(stroke
				(width 0.1)
				(type default)
			)
			(layer "B.Fab")
		)
		(fp_line
			(start -0.67945 -0.3048)
			(end -0.67945 0.3048)
			(stroke
				(width 0.1)
				(type default)
			)
			(layer "B.Fab")
		)
		(fp_line
			(start -0.12065 -0.3048)
			(end -0.67945 -0.3048)
			(stroke
				(width 0.1)
				(type default)
			)
			(layer "B.Fab")
		)
		(fp_line
			(start 0.12065 -0.305054)
			(end 0.12065 -0.2794)
			(stroke
				(width 0.1)
				(type default)
			)
			(layer "B.Fab")
		)
		(fp_line
			(start 0.67945 -0.305054)
			(end 0.12065 -0.305054)
			(stroke
				(width 0.1)
				(type default)
			)
			(layer "B.Fab")
		)
		(pad "1" smd circle
			(at 0.40005 0 90)
			(size 0 0)
			(layers "B.Cu" "B.Mask" "B.Paste")
			(net "P3V3_AUX")
		)
		(pad "2" smd circle
			(at -0.40005 0 90)
			(size 0 0)
			(layers "B.Cu" "B.Mask" "B.Paste")
			(net "GND")
		)
	)
	(footprint ""
		(layer "B.Cu")
		(at 233.553 -240.411 -90)
		(property "Reference" "R359"
			(at 0 0 90)
			(layer "B.SilkS")
			(hide yes)
			(effects
				(font
					(size 1.27 1.27)
				)
				(justify mirror)
			)
		)
		(property "Value" ""
			(at 0 0 90)
			(layer "B.Fab")
			(effects
				(font
					(size 1.27 1.27)
				)
				(justify mirror)
			)
		)
		(duplicate_pad_numbers_are_jumpers no)
		(fp_line
			(start -0.7874 0.4064)
			(end 0.7874 0.4064)
			(stroke
				(width 0.1524)
				(type default)
			)
			(layer "B.SilkS")
		)
		(fp_line
			(start 0.7874 0.4064)
			(end 0.7874 -0.4064)
			(stroke
				(width 0.1524)
				(type default)
			)
			(layer "B.SilkS")
		)
		(fp_line
			(start -0.7874 -0.4064)
			(end -0.7874 0.4064)
			(stroke
				(width 0.1524)
				(type default)
			)
			(layer "B.SilkS")
		)
		(fp_line
			(start 0.7874 -0.4064)
			(end -0.7874 -0.4064)
			(stroke
				(width 0.1524)
				(type default)
			)
			(layer "B.SilkS")
		)
		(fp_line
			(start -0.67945 0.3048)
			(end -0.120396 0.3048)
			(stroke
				(width 0.1)
				(type default)
			)
			(layer "B.Fab")
		)
		(fp_line
			(start -0.120396 0.3048)
			(end -0.120396 0.2794)
			(stroke
				(width 0.1)
				(type default)
			)
			(layer "B.Fab")
		)
		(fp_line
			(start 0.12065 0.3048)
			(end 0.67945 0.3048)
			(stroke
				(width 0.1)
				(type default)
			)
			(layer "B.Fab")
		)
		(fp_line
			(start 0.67945 0.3048)
			(end 0.67945 -0.305054)
			(stroke
				(width 0.1)
				(type default)
			)
			(layer "B.Fab")
		)
		(fp_line
			(start -0.120396 0.2794)
			(end 0.12065 0.2794)
			(stroke
				(width 0.1)
				(type default)
			)
			(layer "B.Fab")
		)
		(fp_line
			(start 0.12065 0.2794)
			(end 0.12065 0.3048)
			(stroke
				(width 0.1)
				(type default)
			)
			(layer "B.Fab")
		)
		(fp_line
			(start -0.12065 -0.2794)
			(end -0.12065 -0.3048)
			(stroke
				(width 0.1)
				(type default)
			)
			(layer "B.Fab")
		)
		(fp_line
			(start 0.12065 -0.2794)
			(end -0.12065 -0.2794)
			(stroke
				(width 0.1)
				(type default)
			)
			(layer "B.Fab")
		)
		(fp_line
			(start -0.67945 -0.3048)
			(end -0.67945 0.3048)
			(stroke
				(width 0.1)
				(type default)
			)
			(layer "B.Fab")
		)
		(fp_line
			(start -0.12065 -0.3048)
			(end -0.67945 -0.3048)
			(stroke
				(width 0.1)
				(type default)
			)
			(layer "B.Fab")
		)
		(fp_line
			(start 0.12065 -0.305054)
			(end 0.12065 -0.2794)
			(stroke
				(width 0.1)
				(type default)
			)
			(layer "B.Fab")
		)
		(fp_line
			(start 0.67945 -0.305054)
			(end 0.12065 -0.305054)
			(stroke
				(width 0.1)
				(type default)
			)
			(layer "B.Fab")
		)
		(pad "1" smd circle
			(at 0.40005 0 90)
			(size 0 0)
			(layers "B.Cu" "B.Mask" "B.Paste")
			(net "PVDD11_S3_P1")
		)
		(pad "2" smd circle
			(at -0.40005 0 90)
			(size 0 0)
			(layers "B.Cu" "B.Mask" "B.Paste")
			(net "SMB_APML_CPU1_SDA")
		)
	)
)
